FILE_TYPE = CONNECTIVITY;
{Allegro Design Entry HDL 16.6-p007 (v16-6-112F) 10/10/2012}
"PAGE_NUMBER" = 272;
0"NC";
1"GND\g";
2"GND\g";
3"GND\g";
4"GND\g";
5"GND\g";
6"GND\g";
7"GND\g";
8"GND\g";
9"GND\g";
10"GND\g";
11"GND\g";
12"GND\g";
13"L3_85OHM_10INCH_DP";
14"L3_85OHM_10INCH_DN";
15"L1_85OHM_10INCH_DN";
16"L5_85OHM_10INCH_DP";
17"L5_85OHM_10INCH_DN";
18"L5_85OHM_10INCH_DP";
19"L5_85OHM_10INCH_DN";
20"L3_85OHM_10INCH_DP";
21"L1_85OHM_10INCH_DP";
22"L10_85OHM_10INCH_DN";
23"L10_85OHM_10INCH_DP";
24"L12_85OHM_10INCH_DP";
25"L12_85OHM_10INCH_DN";
26"L14_85OHM_10INCH_DP";
27"L14_85OHM_10INCH_DN";
28"L12_85OHM_10INCH_DP";
29"L12_85OHM_10INCH_DN";
30"L14_85OHM_10INCH_DP";
31"L14_85OHM_10INCH_DN";
32"L10_85OHM_10INCH_DP";
33"L10_85OHM_10INCH_DN";
34"L1_85OHM_10INCH_DN";
35"L3_85OHM_10INCH_DN";
36"L1_85OHM_10INCH_DP";
%"TEST-PAD-12P-1-GP-U"
"1","(-7600,3425)","0","w_hdl","I1";
;
CDS_SEC"1"
CDS_LOCATION"T1D17"
VALUE"TEST-PAD-12P-1-GP-U"
LOCATION"T1D17"
SEC_TYPE"DISCRET-GB1"
SEC"1"
PACK_TYPE"DISCRET-GB1"
PART_NUMBER"ZZ.00PAD.MJ1"
CDS_LIB"w_hdl"
CDS_LMAN_SYM_OUTLINE"-75,375,75,-375";
"DN"
$PN"2"17;
"DP"
$PN"1"16;
"GND<9>"
$PN"12"8;
"GND<8>"
$PN"11"8;
"GND<7>"
$PN"10"8;
"GND<6>"
$PN"9"8;
"GND<5>"
$PN"8"8;
"GND<4>"
$PN"7"8;
"GND<3>"
$PN"6"8;
"GND<2>"
$PN"5"8;
"GND<1>"
$PN"4"8;
"GND<0>"
$PN"3"8;
%"GND"
"1","(-4775,3075)","0","mstr_symbols","I10";
;
CDS_LIB"mstr_symbols"
SIZE"1B"
VOLTAGE"0.0V"
BODY_TYPE"PLUMBING"
HDL_POWER"GND";
"A\NAC"1;
%"GND"
"1","(-3925,3075)","0","mstr_symbols","I11";
;
VOLTAGE"0.0V"
SIZE"1B"
CDS_LIB"mstr_symbols"
BODY_TYPE"PLUMBING"
HDL_POWER"GND";
"A\NAC"2;
%"TEST-PAD-12P-1-GP-U"
"1","(-3550,3450)","2","w_hdl","I12";
;
CDS_SEC"1"
CDS_LOCATION"T1D24"
VALUE"TEST-PAD-12P-1-GP-U"
LOCATION"T1D24"
SEC_TYPE"DISCRET-GB1"
SEC"1"
PACK_TYPE"DISCRET-GB1"
PART_NUMBER"ZZ.00PAD.MJ1"
CDS_LIB"w_hdl"
CDS_LMAN_SYM_OUTLINE"-75,375,75,-375";
"DN"
$PN"2"30;
"DP"
$PN"1"31;
"GND<9>"
$PN"12"2;
"GND<8>"
$PN"11"2;
"GND<7>"
$PN"10"2;
"GND<6>"
$PN"9"2;
"GND<5>"
$PN"8"2;
"GND<4>"
$PN"7"2;
"GND<3>"
$PN"6"2;
"GND<2>"
$PN"5"2;
"GND<1>"
$PN"4"2;
"GND<0>"
$PN"3"2;
%"GND"
"1","(-6375,4000)","0","mstr_symbols","I13";
;
VOLTAGE"0.0V"
SIZE"1B"
CDS_LIB"mstr_symbols"
BODY_TYPE"PLUMBING"
HDL_POWER"GND";
"A\NAC"3;
%"TEST-PAD-12P-1-GP-U"
"1","(-6000,4375)","2","w_hdl","I14";
;
CDS_SEC"1"
CDS_LOCATION"T1D16"
VALUE"TEST-PAD-12P-1-GP-U"
LOCATION"T1D16"
SEC_TYPE"DISCRET-GB1"
SEC"1"
PACK_TYPE"DISCRET-GB1"
PART_NUMBER"ZZ.00PAD.MJ1"
CDS_LIB"w_hdl"
CDS_LMAN_SYM_OUTLINE"-75,375,75,-375";
"DN"
$PN"2"20;
"DP"
$PN"1"35;
"GND<9>"
$PN"12"3;
"GND<8>"
$PN"11"3;
"GND<7>"
$PN"10"3;
"GND<6>"
$PN"9"3;
"GND<5>"
$PN"8"3;
"GND<4>"
$PN"7"3;
"GND<3>"
$PN"6"3;
"GND<2>"
$PN"5"3;
"GND<1>"
$PN"4"3;
"GND<0>"
$PN"3"3;
%"GND"
"1","(-6375,4950)","0","mstr_symbols","I15";
;
CDS_LIB"mstr_symbols"
SIZE"1B"
VOLTAGE"0.0V"
BODY_TYPE"PLUMBING"
HDL_POWER"GND";
"A\NAC"4;
%"TEST-PAD-12P-1-GP-U"
"1","(-5150,4400)","0","w_hdl","I16";
;
CDS_SEC"1"
CDS_LOCATION"T1D21"
VALUE"TEST-PAD-12P-1-GP-U"
LOCATION"T1D21"
SEC_TYPE"DISCRET-GB1"
SEC"1"
PACK_TYPE"DISCRET-GB1"
PART_NUMBER"ZZ.00PAD.MJ1"
CDS_LIB"w_hdl"
CDS_LMAN_SYM_OUTLINE"-75,375,75,-375";
"DN"
$PN"2"25;
"DP"
$PN"1"24;
"GND<9>"
$PN"12"5;
"GND<8>"
$PN"11"5;
"GND<7>"
$PN"10"5;
"GND<6>"
$PN"9"5;
"GND<5>"
$PN"8"5;
"GND<4>"
$PN"7"5;
"GND<3>"
$PN"6"5;
"GND<2>"
$PN"5"5;
"GND<1>"
$PN"4"5;
"GND<0>"
$PN"3"5;
%"GND"
"1","(-4775,4025)","0","mstr_symbols","I17";
;
CDS_LIB"mstr_symbols"
SIZE"1B"
VOLTAGE"0.0V"
BODY_TYPE"PLUMBING"
HDL_POWER"GND";
"A\NAC"5;
%"GND"
"1","(-3925,4025)","0","mstr_symbols","I18";
;
VOLTAGE"0.0V"
SIZE"1B"
CDS_LIB"mstr_symbols"
BODY_TYPE"PLUMBING"
HDL_POWER"GND";
"A\NAC"6;
%"GND"
"1","(-4775,4975)","0","mstr_symbols","I19";
;
CDS_LIB"mstr_symbols"
SIZE"1B"
VOLTAGE"0.0V"
BODY_TYPE"PLUMBING"
HDL_POWER"GND";
"A\NAC"7;
%"GND"
"1","(-7225,3050)","0","mstr_symbols","I2";
;
CDS_LIB"mstr_symbols"
SIZE"1B"
VOLTAGE"0.0V"
BODY_TYPE"PLUMBING"
HDL_POWER"GND";
"A\NAC"8;
%"GND"
"1","(-3925,4975)","0","mstr_symbols","I20";
;
VOLTAGE"0.0V"
SIZE"1B"
CDS_LIB"mstr_symbols"
BODY_TYPE"PLUMBING"
HDL_POWER"GND";
"A\NAC"9;
%"TEST-PAD-12P-1-GP-U"
"1","(-3550,4400)","2","w_hdl","I21";
;
CDS_SEC"1"
CDS_LOCATION"T1D22"
VALUE"TEST-PAD-12P-1-GP-U"
LOCATION"T1D22"
SEC_TYPE"DISCRET-GB1"
SEC"1"
PACK_TYPE"DISCRET-GB1"
PART_NUMBER"ZZ.00PAD.MJ1"
CDS_LIB"w_hdl"
CDS_LMAN_SYM_OUTLINE"-75,375,75,-375";
"DN"
$PN"2"28;
"DP"
$PN"1"29;
"GND<9>"
$PN"12"6;
"GND<8>"
$PN"11"6;
"GND<7>"
$PN"10"6;
"GND<6>"
$PN"9"6;
"GND<5>"
$PN"8"6;
"GND<4>"
$PN"7"6;
"GND<3>"
$PN"6"6;
"GND<2>"
$PN"5"6;
"GND<1>"
$PN"4"6;
"GND<0>"
$PN"3"6;
%"TEST-PAD-12P-1-GP-U"
"1","(-6000,5325)","2","w_hdl","I22";
;
CDS_SEC"1"
CDS_LOCATION"T1D14"
VALUE"TEST-PAD-12P-1-GP-U"
LOCATION"T1D14"
CDS_LMAN_SYM_OUTLINE"-75,375,75,-375"
CDS_LIB"w_hdl"
PART_NUMBER"ZZ.00PAD.MJ1"
PACK_TYPE"DISCRET-GB1"
SEC"1"
SEC_TYPE"DISCRET-GB1";
"DN"
$PN"2"21;
"DP"
$PN"1"34;
"GND<9>"
$PN"12"4;
"GND<8>"
$PN"11"4;
"GND<7>"
$PN"10"4;
"GND<6>"
$PN"9"4;
"GND<5>"
$PN"8"4;
"GND<4>"
$PN"7"4;
"GND<3>"
$PN"6"4;
"GND<2>"
$PN"5"4;
"GND<1>"
$PN"4"4;
"GND<0>"
$PN"3"4;
%"TEST-PAD-12P-1-GP-U"
"1","(-5150,5350)","0","w_hdl","I23";
;
CDS_SEC"1"
CDS_LOCATION"T1D19"
VALUE"TEST-PAD-12P-1-GP-U"
LOCATION"T1D19"
SEC_TYPE"DISCRET-GB1"
SEC"1"
PACK_TYPE"DISCRET-GB1"
PART_NUMBER"ZZ.00PAD.MJ1"
CDS_LIB"w_hdl"
CDS_LMAN_SYM_OUTLINE"-75,375,75,-375";
"DN"
$PN"2"22;
"DP"
$PN"1"23;
"GND<9>"
$PN"12"7;
"GND<8>"
$PN"11"7;
"GND<7>"
$PN"10"7;
"GND<6>"
$PN"9"7;
"GND<5>"
$PN"8"7;
"GND<4>"
$PN"7"7;
"GND<3>"
$PN"6"7;
"GND<2>"
$PN"5"7;
"GND<1>"
$PN"4"7;
"GND<0>"
$PN"3"7;
%"TEST-PAD-12P-1-GP-U"
"1","(-3550,5350)","2","w_hdl","I24";
;
CDS_SEC"1"
CDS_LOCATION"T1D20"
VALUE"TEST-PAD-12P-1-GP-U"
LOCATION"T1D20"
SEC_TYPE"DISCRET-GB1"
SEC"1"
PACK_TYPE"DISCRET-GB1"
PART_NUMBER"ZZ.00PAD.MJ1"
CDS_LIB"w_hdl"
CDS_LMAN_SYM_OUTLINE"-75,375,75,-375";
"DN"
$PN"2"32;
"DP"
$PN"1"33;
"GND<9>"
$PN"12"9;
"GND<8>"
$PN"11"9;
"GND<7>"
$PN"10"9;
"GND<6>"
$PN"9"9;
"GND<5>"
$PN"8"9;
"GND<4>"
$PN"7"9;
"GND<3>"
$PN"6"9;
"GND<2>"
$PN"5"9;
"GND<1>"
$PN"4"9;
"GND<0>"
$PN"3"9;
%"TEST-PAD-12P-1-GP-U"
"1","(-7600,4375)","0","w_hdl","I3";
;
CDS_SEC"1"
CDS_LOCATION"T1D15"
VALUE"TEST-PAD-12P-1-GP-U"
LOCATION"T1D15"
SEC_TYPE"DISCRET-GB1"
SEC"1"
PACK_TYPE"DISCRET-GB1"
PART_NUMBER"ZZ.00PAD.MJ1"
CDS_LIB"w_hdl"
CDS_LMAN_SYM_OUTLINE"-75,375,75,-375";
"DN"
$PN"2"14;
"DP"
$PN"1"13;
"GND<9>"
$PN"12"10;
"GND<8>"
$PN"11"10;
"GND<7>"
$PN"10"10;
"GND<6>"
$PN"9"10;
"GND<5>"
$PN"8"10;
"GND<4>"
$PN"7"10;
"GND<3>"
$PN"6"10;
"GND<2>"
$PN"5"10;
"GND<1>"
$PN"4"10;
"GND<0>"
$PN"3"10;
%"GND"
"1","(-7225,4000)","0","mstr_symbols","I4";
;
CDS_LIB"mstr_symbols"
SIZE"1B"
VOLTAGE"0.0V"
BODY_TYPE"PLUMBING"
HDL_POWER"GND";
"A\NAC"10;
%"TEST-PAD-12P-1-GP-U"
"1","(-7600,5325)","0","w_hdl","I5";
;
CDS_SEC"1"
CDS_LOCATION"T1D13"
VALUE"TEST-PAD-12P-1-GP-U"
LOCATION"T1D13"
CDS_LMAN_SYM_OUTLINE"-75,375,75,-375"
CDS_LIB"w_hdl"
PART_NUMBER"ZZ.00PAD.MJ1"
PACK_TYPE"DISCRET-GB1"
SEC"1"
SEC_TYPE"DISCRET-GB1";
"DN"
$PN"2"15;
"DP"
$PN"1"36;
"GND<9>"
$PN"12"11;
"GND<8>"
$PN"11"11;
"GND<7>"
$PN"10"11;
"GND<6>"
$PN"9"11;
"GND<5>"
$PN"8"11;
"GND<4>"
$PN"7"11;
"GND<3>"
$PN"6"11;
"GND<2>"
$PN"5"11;
"GND<1>"
$PN"4"11;
"GND<0>"
$PN"3"11;
%"GND"
"1","(-7225,4950)","0","mstr_symbols","I6";
;
VOLTAGE"0.0V"
SIZE"1B"
CDS_LIB"mstr_symbols"
BODY_TYPE"PLUMBING"
HDL_POWER"GND";
"A\NAC"11;
%"GND"
"1","(-6375,3050)","0","mstr_symbols","I7";
;
VOLTAGE"0.0V"
SIZE"1B"
CDS_LIB"mstr_symbols"
BODY_TYPE"PLUMBING"
HDL_POWER"GND";
"A\NAC"12;
%"TEST-PAD-12P-1-GP-U"
"1","(-6000,3425)","2","w_hdl","I8";
;
CDS_SEC"1"
CDS_LOCATION"T1D18"
VALUE"TEST-PAD-12P-1-GP-U"
LOCATION"T1D18"
SEC_TYPE"DISCRET-GB1"
SEC"1"
PACK_TYPE"DISCRET-GB1"
PART_NUMBER"ZZ.00PAD.MJ1"
CDS_LIB"w_hdl"
CDS_LMAN_SYM_OUTLINE"-75,375,75,-375";
"DN"
$PN"2"18;
"DP"
$PN"1"19;
"GND<9>"
$PN"12"12;
"GND<8>"
$PN"11"12;
"GND<7>"
$PN"10"12;
"GND<6>"
$PN"9"12;
"GND<5>"
$PN"8"12;
"GND<4>"
$PN"7"12;
"GND<3>"
$PN"6"12;
"GND<2>"
$PN"5"12;
"GND<1>"
$PN"4"12;
"GND<0>"
$PN"3"12;
%"TEST-PAD-12P-1-GP-U"
"1","(-5150,3450)","0","w_hdl","I9";
;
CDS_SEC"1"
CDS_LOCATION"T1D23"
VALUE"TEST-PAD-12P-1-GP-U"
LOCATION"T1D23"
SEC_TYPE"DISCRET-GB1"
SEC"1"
PACK_TYPE"DISCRET-GB1"
PART_NUMBER"ZZ.00PAD.MJ1"
CDS_LIB"w_hdl"
CDS_LMAN_SYM_OUTLINE"-75,375,75,-375";
"DN"
$PN"2"27;
"DP"
$PN"1"26;
"GND<9>"
$PN"12"1;
"GND<8>"
$PN"11"1;
"GND<7>"
$PN"10"1;
"GND<6>"
$PN"9"1;
"GND<5>"
$PN"8"1;
"GND<4>"
$PN"7"1;
"GND<3>"
$PN"6"1;
"GND<2>"
$PN"5"1;
"GND<1>"
$PN"4"1;
"GND<0>"
$PN"3"1;
END.
